# BASEBOARD_FAB2 (Tioga Pass) — schematic netlist excerpt (pin names and nets, part order shuffled) for the footprints in the layout excerpt that follows; sources: Cadence DE-HDL packaged netlist, KiCad conversion of Wiwynn_Tioga_Pass_MB.brd

C2P6  CAP_A  0.1UF 16V 10% X7R  pkg 0402V  page 192 : A = P3V3_STBY ; B = GND

U7W1  PI5A3157BC6E-GP  pkg DISCRET-GC2  page 166
  B1  = PECI_BMC
  GND  = GND
  B0  = PECI_PCH
  A  = PECI_CPU_G
  VCC  = P3V3_STBY
  S  = PECI_SEL

(kicad_pcb
	(version 20260206)
	(generator "pcbnew")
	(generator_version "10.0")
	(general
		(thickness 1.6)
		(legacy_teardrops no)
	)
	(paper "A4")
	(title_block
		(title "Wiwynn_Tioga_Pass_MB.brd")
		(comment 1 "Tioga Pass / footprints 4218-4219 of 4770")
	)
	(layers
		(0 "F.Cu" signal "TOP")
		(4 "In1.Cu" signal "L2GND")
		(6 "In2.Cu" signal "L3")
		(8 "In3.Cu" signal "L4GND")
		(10 "In4.Cu" signal "L5")
		(12 "In5.Cu" signal "L6GND")
		(14 "In6.Cu" signal "L7VCC")
		(16 "In7.Cu" signal "L8VCC")
		(18 "In8.Cu" signal "L9GND")
		(20 "In9.Cu" signal "L10")
		(22 "In10.Cu" signal "L11GND")
		(24 "In11.Cu" signal "L12")
		(26 "In12.Cu" signal "L13GND")
		(2 "B.Cu" signal "BOTTOM")
		(9 "F.Adhes" user "F.Adhesive")
		(11 "B.Adhes" user "B.Adhesive")
		(13 "F.Paste" user "Package Geometry/Pastemask Top")
		(15 "B.Paste" user "Package Geometry/Pastemask Bottom")
		(5 "F.SilkS" user "Ref Des/Silkscreen Top")
		(7 "B.SilkS" user "Ref Des/Silkscreen Bottom")
		(1 "F.Mask" user "Board Geometry/Soldermask Top")
		(3 "B.Mask" user "Board Geometry/Soldermask Bottom")
		(17 "Dwgs.User" user "User.Drawings")
		(19 "Cmts.User" user "User.Comments")
		(21 "Eco1.User" user "User.Eco1")
		(23 "Eco2.User" user "User.Eco2")
		(25 "Edge.Cuts" user "Board Geometry/Outline")
		(27 "Margin" user)
		(31 "F.CrtYd" user "Package Geometry/Place Bound Top")
		(29 "B.CrtYd" user "Package Geometry/Place Bound Bottom")
		(35 "F.Fab" user "Ref Des/Assembly Top")
		(33 "B.Fab" user "Ref Des/Assembly Bottom")
	)
	(footprint ""
		(layer "B.Cu")
		(at 381.127 -82.423 90)
		(property "Reference" "U7W1"
			(at 0 0 90)
			(layer "B.SilkS")
			(hide yes)
			(effects
				(font
					(size 1.27 1.27)
				)
				(justify mirror)
			)
		)
		(property "Value" "*"
			(at 2.3622 -8.3185 90)
			(unlocked yes)
			(layer "B.Fab")
			(hide yes)
			(effects
				(font
					(size 1.27 1.016)
					(thickness 0.1524)
				)
				(justify mirror)
			)
		)
		(property "Device Type" "PI5A3157BC6E-GP_DISCRET-GC2-PIA"
			(at 2.3622 -10.2235 90)
			(unlocked yes)
			(layer "B.Fab")
			(hide yes)
			(effects
				(font
					(size 1.27 1.016)
					(thickness 0.1524)
				)
				(justify mirror)
			)
		)
		(duplicate_pad_numbers_are_jumpers no)
		(fp_line
			(start 1.4478 -1.7018)
			(end 1.4478 1.7018)
			(stroke
				(width 0.1524)
				(type default)
			)
			(layer "B.SilkS")
		)
		(fp_line
			(start -1.4478 -1.7018)
			(end 1.4478 -1.7018)
			(stroke
				(width 0.1524)
				(type default)
			)
			(layer "B.SilkS")
		)
		(fp_line
			(start 1.4478 1.7018)
			(end -1.4478 1.7018)
			(stroke
				(width 0.1524)
				(type default)
			)
			(layer "B.SilkS")
		)
		(fp_line
			(start -1.4478 1.7018)
			(end -1.4478 -1.7018)
			(stroke
				(width 0.1524)
				(type default)
			)
			(layer "B.SilkS")
		)
		(fp_line
			(start 1.5494 1.7907)
			(end 1.5494 0.8255)
			(stroke
				(width 0.3302)
				(type default)
			)
			(layer "B.SilkS")
		)
		(fp_line
			(start 0.5715 1.7907)
			(end 1.5494 1.7907)
			(stroke
				(width 0.3302)
				(type default)
			)
			(layer "B.SilkS")
		)
		(fp_poly
			(pts
				(xy 0.6604 1.7272) (xy 1.016 2.0828) (xy 0.3048 2.0828)
			)
			(stroke
				(width 0)
				(type default)
			)
			(fill yes)
			(layer "B.SilkS")
		)
		(fp_poly
			(pts
				(xy 1.524 -1.778) (xy -1.524 -1.778) (xy -1.524 1.778) (xy 1.524 1.778)
			)
			(stroke
				(width 0)
				(type default)
			)
			(fill no)
			(layer "B.CrtYd")
		)
		(fp_poly
			(pts
				(xy 1.524 -1.778) (xy -1.524 -1.778) (xy -1.524 1.778) (xy 1.524 1.778)
			)
			(stroke
				(width 0)
				(type default)
			)
			(fill no)
			(layer "B.Fab")
		)
		(pad "1" smd rect
			(at 0.65024 0.9398 270)
			(size 0.4064 1.016)
			(layers "B.Cu" "B.Mask" "B.Paste")
			(net "PECI_BMC")
		)
		(pad "2" smd rect
			(at 0 0.9398 270)
			(size 0.4064 1.016)
			(layers "B.Cu" "B.Mask" "B.Paste")
			(net "GND")
		)
		(pad "3" smd rect
			(at -0.65024 0.9398 270)
			(size 0.4064 1.016)
			(layers "B.Cu" "B.Mask" "B.Paste")
			(net "PECI_PCH")
		)
		(pad "4" smd rect
			(at -0.65024 -0.9398 270)
			(size 0.4064 1.016)
			(layers "B.Cu" "B.Mask" "B.Paste")
			(net "PECI_CPU_G")
		)
		(pad "5" smd rect
			(at 0 -0.9398 270)
			(size 0.4064 1.016)
			(layers "B.Cu" "B.Mask" "B.Paste")
			(net "P3V3_STBY")
		)
		(pad "6" smd rect
			(at 0.65024 -0.9398 270)
			(size 0.4064 1.016)
			(layers "B.Cu" "B.Mask" "B.Paste")
			(net "PECI_SEL")
		)
	)
	(footprint ""
		(layer "B.Cu")
		(at 376.344688 -69.895466 180)
		(property "Reference" "C2P6"
			(at 0 0 0)
			(layer "B.SilkS")
			(hide yes)
			(effects
				(font
					(size 1.27 1.27)
				)
				(justify mirror)
			)
		)
		(property "Value" ""
			(at 0 0 0)
			(layer "B.Fab")
			(effects
				(font
					(size 1.27 1.27)
				)
				(justify mirror)
			)
		)
		(duplicate_pad_numbers_are_jumpers no)
		(fp_rect
			(start 0.2794 0.9144)
			(end -0.2794 -0.1143)
			(stroke
				(width 0)
				(type default)
			)
			(fill no)
			(layer "B.CrtYd")
		)
		(fp_line
			(start 0.2794 0.9144)
			(end 0.2794 -0.1143)
			(stroke
				(width 0.1)
				(type default)
			)
			(layer "B.Fab")
		)
		(fp_line
			(start 0.2794 -0.1143)
			(end -0.2794 -0.1143)
			(stroke
				(width 0.1)
				(type default)
			)
			(layer "B.Fab")
		)
		(fp_line
			(start -0.2794 0.9144)
			(end 0.2794 0.9144)
			(stroke
				(width 0.1)
				(type default)
			)
			(layer "B.Fab")
		)
		(fp_line
			(start -0.2794 -0.1143)
			(end -0.2794 0.9144)
			(stroke
				(width 0.1)
				(type default)
			)
			(layer "B.Fab")
		)
		(pad "1" smd custom
			(at 0 0 90)
			(size 0.10414 0.10414)
			(layers "B.Cu" "B.Mask" "B.Paste")
			(net "P3V3_STBY")
			(options
				(clearance outline)
				(anchor circle)
			)
			(primitives
				(gr_poly
					(pts
						(xy -0.20828 -0.08636) (xy -0.20828 0.08636) (xy -0.08636 0.20828) (xy 0.086614 0.20828) (xy 0.20828 0.086614)
						(xy 0.20828 -0.08636) (xy 0.08636 -0.20828) (xy -0.08636 -0.20828)
					)
					(width 0)
					(fill yes)
				)
			)
		)
		(pad "2" smd custom
			(at 0 0.8001 90)
			(size 0.10414 0.10414)
			(layers "B.Cu" "B.Mask" "B.Paste")
			(net "GND")
			(options
				(clearance outline)
				(anchor circle)
			)
			(primitives
				(gr_poly
					(pts
						(xy -0.20828 -0.08636) (xy -0.20828 0.08636) (xy -0.08636 0.20828) (xy 0.086614 0.20828) (xy 0.20828 0.086614)
						(xy 0.20828 -0.08636) (xy 0.08636 -0.20828) (xy -0.08636 -0.20828)
					)
					(width 0)
					(fill yes)
				)
			)
		)
		(zone
			(layer "B.Cu")
			(hatch none 0.5)
			(connect_pads
				(clearance 0)
			)
			(min_thickness 0.25)
			(keepout
				(tracks not_allowed)
				(vias allowed)
				(pads allowed)
				(copperpour not_allowed)
				(footprints allowed)
			)
			(placement
				(enabled no)
				(sheetname "")
			)
			(fill
				(thermal_gap 0.5)
				(thermal_bridge_width 0.5)
				(island_removal_mode 0)
			)
			(polygon
				(pts
					(xy 376.257058 -70.105016) (xy 376.257058 -70.486016) (xy 376.432318 -70.486016) (xy 376.432572 -70.105016)
				)
			)
		)
		(zone
			(layer "B.Cu")
			(hatch none 0.5)
			(connect_pads
				(clearance 0)
			)
			(min_thickness 0.25)
			(keepout
				(tracks allowed)
				(vias not_allowed)
				(pads allowed)
				(copperpour not_allowed)
				(footprints allowed)
			)
			(placement
				(enabled no)
				(sheetname "")
			)
			(fill
				(thermal_gap 0.5)
				(thermal_bridge_width 0.5)
				(island_removal_mode 0)
			)
			(polygon
				(pts
					(xy 376.257058 -70.105016) (xy 376.257058 -70.486016) (xy 376.432318 -70.486016) (xy 376.432572 -70.105016)
				)
			)
		)
	)
)
